# S9S_MB_2U (Grand Teton) — schematic netlist excerpt (pin names and nets, part order shuffled) for the footprints in the layout excerpt that follows; sources: Cadence DE-HDL packaged netlist, KiCad conversion of 03242023_DA0F0TMBIJ0_F0T_Motherboard_J_brd_V01_OCP.brd

C2393  Q_CAP  0.1UF 25V 10% EMPTY  pkg 0402  page 306 : A = U369_VDD ; B = GND

Q98  MOSFET_NCH_DUAL  NX6008NBKS IC  pkg SOT363XB  page 256
  S1  = GND
  G1  = RST_PLD_CPU0_DRAM_AB_N
  D2  = LED_RST_PLD_CPU0_DRAM_CD_N_D
  S2  = GND
  G2  = RST_PLD_CPU0_DRAM_CD_N
  D1  = LED_RST_PLD_CPU0_DRAM_AB_N_D

(kicad_pcb
	(version 20260206)
	(generator "pcbnew")
	(generator_version "10.0")
	(general
		(thickness 1.6)
		(legacy_teardrops no)
	)
	(paper "A4")
	(title_block
		(title "03242023_DA0F0TMBIJ0_F0T_Motherboard_J_brd_V01_OCP.brd")
		(comment 1 "Grand Teton / footprints 2337-2338 of 6105")
	)
	(layers
		(0 "F.Cu" signal "TOP")
		(4 "In1.Cu" signal "GND")
		(6 "In2.Cu" signal "IN1")
		(8 "In3.Cu" signal "GND1")
		(10 "In4.Cu" signal "IN2")
		(12 "In5.Cu" signal "GND2")
		(14 "In6.Cu" signal "IN3")
		(16 "In7.Cu" signal "GND3")
		(18 "In8.Cu" signal "VCC")
		(20 "In9.Cu" signal "VCC1")
		(22 "In10.Cu" signal "GND4")
		(24 "In11.Cu" signal "IN4")
		(26 "In12.Cu" signal "GND5")
		(28 "In13.Cu" signal "IN5")
		(30 "In14.Cu" signal "GND6")
		(32 "In15.Cu" signal "IN6")
		(34 "In16.Cu" signal "GND7")
		(2 "B.Cu" signal "BOTTOM")
		(9 "F.Adhes" user "F.Adhesive")
		(11 "B.Adhes" user "B.Adhesive")
		(13 "F.Paste" user "Package Geometry/Pastemask Top")
		(15 "B.Paste" user "Package Geometry/Pastemask Bottom")
		(5 "F.SilkS" user "Ref Des/Silkscreen Top")
		(7 "B.SilkS" user "Ref Des/Silkscreen Bottom")
		(1 "F.Mask" user "Board Geometry/Soldermask Top")
		(3 "B.Mask" user "Board Geometry/Soldermask Bottom")
		(17 "Dwgs.User" user "User.Drawings")
		(19 "Cmts.User" user "User.Comments")
		(21 "Eco1.User" user "User.Eco1")
		(23 "Eco2.User" user "User.Eco2")
		(25 "Edge.Cuts" user "Board Geometry/Outline")
		(27 "Margin" user)
		(31 "F.CrtYd" user "Package Geometry/Place Bound Top")
		(29 "B.CrtYd" user "Package Geometry/Place Bound Bottom")
		(35 "F.Fab" user "Ref Des/Assembly Top")
		(33 "B.Fab" user "Ref Des/Assembly Bottom")
	)
	(footprint ""
		(layer "F.Cu")
		(at 94.045278 -93.063314)
		(property "Reference" "Q98"
			(at 0.57658 1.975612 0)
			(unlocked yes)
			(layer "F.SilkS")
			(effects
				(font
					(size 0.7874 0.5842)
					(thickness 0.1524)
				)
			)
		)
		(property "Value" ""
			(at 0 0 0)
			(layer "F.Fab")
			(effects
				(font
					(size 1.27 1.27)
				)
			)
		)
		(duplicate_pad_numbers_are_jumpers no)
		(fp_line
			(start -1.376172 -1.199896)
			(end -0.508 -1.199896)
			(stroke
				(width 0.1524)
				(type default)
			)
			(layer "F.SilkS")
		)
		(fp_line
			(start -1.376172 1.199896)
			(end -1.376172 -1.199896)
			(stroke
				(width 0.1524)
				(type default)
			)
			(layer "F.SilkS")
		)
		(fp_line
			(start -0.508 -1.199896)
			(end 0 -0.762)
			(stroke
				(width 0.1524)
				(type default)
			)
			(layer "F.SilkS")
		)
		(fp_line
			(start 0 -0.762)
			(end 0.508 -1.199896)
			(stroke
				(width 0.1524)
				(type default)
			)
			(layer "F.SilkS")
		)
		(fp_line
			(start 0.508 -1.199896)
			(end 1.376172 -1.199896)
			(stroke
				(width 0.1524)
				(type default)
			)
			(layer "F.SilkS")
		)
		(fp_line
			(start 1.376172 -1.199896)
			(end 1.376172 1.199896)
			(stroke
				(width 0.1524)
				(type default)
			)
			(layer "F.SilkS")
		)
		(fp_line
			(start 1.376172 1.199896)
			(end -1.376172 1.199896)
			(stroke
				(width 0.1524)
				(type default)
			)
			(layer "F.SilkS")
		)
		(fp_poly
			(pts
				(xy -1.4605 -0.7493) (xy -2.2225 -0.3683) (xy -2.2225 -1.1303)
			)
			(stroke
				(width 0)
				(type default)
			)
			(fill yes)
			(layer "F.SilkS")
		)
		(fp_line
			(start -0.674878 -1.100074)
			(end 0.674878 -1.100074)
			(stroke
				(width 0.1)
				(type default)
			)
			(layer "F.Fab")
		)
		(fp_line
			(start -0.674878 1.100074)
			(end -0.674878 -1.100074)
			(stroke
				(width 0.1)
				(type default)
			)
			(layer "F.Fab")
		)
		(fp_line
			(start 0.674878 -1.100074)
			(end 0.674878 1.100074)
			(stroke
				(width 0.1)
				(type default)
			)
			(layer "F.Fab")
		)
		(fp_line
			(start 0.674878 1.100074)
			(end -0.674878 1.100074)
			(stroke
				(width 0.1)
				(type default)
			)
			(layer "F.Fab")
		)
		(fp_poly
			(pts
				(xy -1.4605 -0.7493) (xy -2.2225 -1.1303) (xy -2.2225 -0.3683)
			)
			(stroke
				(width 0)
				(type default)
			)
			(fill yes)
			(layer "F.Fab")
		)
		(pad "1" smd rect
			(at -0.899922 -0.750062 270)
			(size 0.6096 0.6096)
			(layers "F.Cu" "F.Mask" "F.Paste")
			(net "GND")
		)
		(pad "2" smd rect
			(at -0.899922 0 270)
			(size 0.4064 0.6096)
			(layers "F.Cu" "F.Mask" "F.Paste")
			(net "RST_PLD_CPU0_DRAM_AB_N")
		)
		(pad "3" smd rect
			(at -0.899922 0.750062 270)
			(size 0.6096 0.6096)
			(layers "F.Cu" "F.Mask" "F.Paste")
			(net "LED_RST_PLD_CPU0_DRAM_CD_N_D")
		)
		(pad "4" smd rect
			(at 0.899922 0.750062 270)
			(size 0.6096 0.6096)
			(layers "F.Cu" "F.Mask" "F.Paste")
			(net "GND")
		)
		(pad "5" smd rect
			(at 0.899922 0 270)
			(size 0.4064 0.6096)
			(layers "F.Cu" "F.Mask" "F.Paste")
			(net "RST_PLD_CPU0_DRAM_CD_N")
		)
		(pad "6" smd rect
			(at 0.899922 -0.750062 270)
			(size 0.6096 0.6096)
			(layers "F.Cu" "F.Mask" "F.Paste")
			(net "LED_RST_PLD_CPU0_DRAM_AB_N_D")
		)
	)
	(footprint ""
		(layer "F.Cu")
		(at 279.40762 -425.69638)
		(property "Reference" "C2393"
			(at 0 0 0)
			(layer "F.SilkS")
			(hide yes)
			(effects
				(font
					(size 1.27 1.27)
				)
			)
		)
		(property "Value" ""
			(at 0 0 0)
			(layer "F.Fab")
			(effects
				(font
					(size 1.27 1.27)
				)
			)
		)
		(duplicate_pad_numbers_are_jumpers no)
		(fp_line
			(start -0.7874 -0.4064)
			(end 0.7874 -0.4064)
			(stroke
				(width 0.1524)
				(type default)
			)
			(layer "F.SilkS")
		)
		(fp_line
			(start -0.7874 0.4064)
			(end -0.7874 -0.4064)
			(stroke
				(width 0.1524)
				(type default)
			)
			(layer "F.SilkS")
		)
		(fp_line
			(start 0.7874 -0.4064)
			(end 0.7874 0.4064)
			(stroke
				(width 0.1524)
				(type default)
			)
			(layer "F.SilkS")
		)
		(fp_line
			(start 0.7874 0.4064)
			(end -0.7874 0.4064)
			(stroke
				(width 0.1524)
				(type default)
			)
			(layer "F.SilkS")
		)
		(fp_line
			(start -0.67945 -0.305054)
			(end -0.12065 -0.305054)
			(stroke
				(width 0.1)
				(type default)
			)
			(layer "F.Fab")
		)
		(fp_line
			(start -0.67945 0.3048)
			(end -0.67945 -0.305054)
			(stroke
				(width 0.1)
				(type default)
			)
			(layer "F.Fab")
		)
		(fp_line
			(start -0.12065 -0.305054)
			(end -0.12065 -0.2794)
			(stroke
				(width 0.1)
				(type default)
			)
			(layer "F.Fab")
		)
		(fp_line
			(start -0.12065 -0.2794)
			(end 0.12065 -0.2794)
			(stroke
				(width 0.1)
				(type default)
			)
			(layer "F.Fab")
		)
		(fp_line
			(start -0.12065 0.2794)
			(end -0.12065 0.3048)
			(stroke
				(width 0.1)
				(type default)
			)
			(layer "F.Fab")
		)
		(fp_line
			(start -0.12065 0.3048)
			(end -0.67945 0.3048)
			(stroke
				(width 0.1)
				(type default)
			)
			(layer "F.Fab")
		)
		(fp_line
			(start 0.120396 0.2794)
			(end -0.12065 0.2794)
			(stroke
				(width 0.1)
				(type default)
			)
			(layer "F.Fab")
		)
		(fp_line
			(start 0.120396 0.3048)
			(end 0.120396 0.2794)
			(stroke
				(width 0.1)
				(type default)
			)
			(layer "F.Fab")
		)
		(fp_line
			(start 0.12065 -0.3048)
			(end 0.67945 -0.3048)
			(stroke
				(width 0.1)
				(type default)
			)
			(layer "F.Fab")
		)
		(fp_line
			(start 0.12065 -0.2794)
			(end 0.12065 -0.3048)
			(stroke
				(width 0.1)
				(type default)
			)
			(layer "F.Fab")
		)
		(fp_line
			(start 0.67945 -0.3048)
			(end 0.67945 0.3048)
			(stroke
				(width 0.1)
				(type default)
			)
			(layer "F.Fab")
		)
		(fp_line
			(start 0.67945 0.3048)
			(end 0.120396 0.3048)
			(stroke
				(width 0.1)
				(type default)
			)
			(layer "F.Fab")
		)
		(pad "1" smd circle
			(at -0.40005 0)
			(size 0 0)
			(layers "F.Cu" "F.Mask" "F.Paste")
			(net "U369_VDD")
		)
		(pad "2" smd circle
			(at 0.40005 0)
			(size 0 0)
			(layers "F.Cu" "F.Mask" "F.Paste")
			(net "GND")
		)
	)
)
